(kicad_pcb
	(version 20260206)
	(generator "pcbnew")
	(generator_version "10.0")
	(general
		(thickness 1.6)
		(legacy_teardrops no)
	)
	(paper "A4")
	(title_block
		(title "fcb — Lightning_FCB_BRD.brd")
		(comment 1 "Lightning (Wiwynn / Facebook NVMe JBOF) / footprints 32-38 of 495")
	)
	(layers
		(0 "F.Cu" signal "TOP")
		(4 "In1.Cu" signal "L2GND")
		(6 "In2.Cu" signal "L3VCC")
		(2 "B.Cu" signal "BOTTOM")
		(9 "F.Adhes" user "F.Adhesive")
		(11 "B.Adhes" user "B.Adhesive")
		(13 "F.Paste" user "Package Geometry/Pastemask Top")
		(15 "B.Paste" user "Package Geometry/Pastemask Bottom")
		(5 "F.SilkS" user "Ref Des/Silkscreen Top")
		(7 "B.SilkS" user "Ref Des/Silkscreen Bottom")
		(1 "F.Mask" user "Board Geometry/Soldermask Top")
		(3 "B.Mask" user "Board Geometry/Soldermask Bottom")
		(17 "Dwgs.User" user "User.Drawings")
		(19 "Cmts.User" user "User.Comments")
		(21 "Eco1.User" user "User.Eco1")
		(23 "Eco2.User" user "User.Eco2")
		(25 "Edge.Cuts" user "Board Geometry/Outline")
		(27 "Margin" user)
		(31 "F.CrtYd" user "Package Geometry/Place Bound Top")
		(29 "B.CrtYd" user "Package Geometry/Place Bound Bottom")
		(35 "F.Fab" user "Ref Des/Assembly Top")
		(33 "B.Fab" user "Ref Des/Assembly Bottom")
	)
	(footprint ""
		(layer "F.Cu")
		(at 23.749 -101.219 90)
		(property "Reference" "TC4"
			(at 0 0 90)
			(layer "F.SilkS")
			(hide yes)
			(effects
				(font
					(size 1.27 1.27)
				)
			)
		)
		(property "Value" "ST15U25VDM-1-GP"
			(at 0 -9.6012 90)
			(unlocked yes)
			(layer "F.Fab")
			(hide yes)
			(effects
				(font
					(size 1.016 1.016)
					(thickness 0.1524)
				)
			)
		)
		(property "Device Type" "CT7343H79"
			(at 0 -11.1252 90)
			(unlocked yes)
			(layer "F.Fab")
			(hide yes)
			(effects
				(font
					(size 1.016 1.016)
					(thickness 0.1524)
				)
			)
		)
		(duplicate_pad_numbers_are_jumpers no)
		(fp_line
			(start 2.286 -4.8768)
			(end -2.286 -4.8768)
			(stroke
				(width 0.1524)
				(type default)
			)
			(layer "F.SilkS")
		)
		(fp_line
			(start -2.286 -4.8768)
			(end -2.286 -2.032)
			(stroke
				(width 0.1524)
				(type default)
			)
			(layer "F.SilkS")
		)
		(fp_line
			(start 2.1082 -4.699)
			(end -2.1082 -4.699)
			(stroke
				(width 0.508)
				(type default)
			)
			(layer "F.SilkS")
		)
		(fp_line
			(start 2.286 -2.032)
			(end 2.286 -4.8768)
			(stroke
				(width 0.1524)
				(type default)
			)
			(layer "F.SilkS")
		)
		(fp_line
			(start 2.286 2.032)
			(end 2.286 4.8768)
			(stroke
				(width 0.1524)
				(type default)
			)
			(layer "F.SilkS")
		)
		(fp_line
			(start 2.286 4.8768)
			(end -2.286 4.8768)
			(stroke
				(width 0.1524)
				(type default)
			)
			(layer "F.SilkS")
		)
		(fp_line
			(start -2.286 4.8768)
			(end -2.286 2.032)
			(stroke
				(width 0.1524)
				(type default)
			)
			(layer "F.SilkS")
		)
		(fp_rect
			(start -2.1463 3.6449)
			(end 2.1463 -3.6449)
			(stroke
				(width 0)
				(type default)
			)
			(fill no)
			(layer "F.CrtYd")
		)
		(fp_poly
			(pts
				(xy -2.54 4.953) (xy -2.54 4.2926) (xy -3.81 4.2926) (xy -3.81 -4.2926) (xy -2.54 -4.2926) (xy -2.54 -4.953)
				(xy 2.54 -4.953) (xy 2.54 -4.2926) (xy 3.81 -4.2926) (xy 3.81 -1.6256) (xy 2.1463 -1.6256) (xy 2.1463 -3.6449)
				(xy -2.1463 -3.6449) (xy -2.1463 3.6449) (xy 2.1463 3.6449) (xy 2.1463 -1.6129) (xy 3.81 -1.6129)
				(xy 3.81 4.2926) (xy 2.54 4.2926) (xy 2.54 4.953)
			)
			(stroke
				(width 0)
				(type default)
			)
			(fill no)
			(layer "F.CrtYd")
		)
		(fp_rect
			(start 2.54 4.2926)
			(end 3.81 -4.2926)
			(stroke
				(width 0)
				(type default)
			)
			(fill no)
			(layer "F.Fab")
		)
		(fp_rect
			(start -3.81 4.2926)
			(end -2.54 -4.2926)
			(stroke
				(width 0)
				(type default)
			)
			(fill no)
			(layer "F.Fab")
		)
		(fp_rect
			(start -2.54 4.953)
			(end 2.54 -4.953)
			(stroke
				(width 0)
				(type default)
			)
			(fill no)
			(layer "F.Fab")
		)
		(pad "1" smd rect
			(at 0 -3.1496 90)
			(size 2.413 2.286)
			(layers "F.Cu" "F.Mask" "F.Paste")
			(net "P12VU")
		)
		(pad "2" smd rect
			(at 0 3.1496 90)
			(size 2.413 2.286)
			(layers "F.Cu" "F.Mask" "F.Paste")
			(net "GND")
		)
		(zone
			(layer "F.Cu")
			(hatch none 0.5)
			(connect_pads
				(clearance 0)
			)
			(min_thickness 0.25)
			(keepout
				(tracks allowed)
				(vias not_allowed)
				(pads allowed)
				(copperpour not_allowed)
				(footprints allowed)
			)
			(placement
				(enabled no)
				(sheetname "")
			)
			(fill
				(thermal_gap 0.5)
				(thermal_bridge_width 0.5)
				(island_removal_mode 0)
			)
			(polygon
				(pts
					(xy 22.0599 -102.7303) (xy 19.1516 -102.7303) (xy 19.1516 -99.7077) (xy 22.0472 -99.7077) (xy 22.3774 -99.7077)
					(xy 22.3774 -102.7303)
				)
			)
		)
		(zone
			(layer "F.Cu")
			(hatch none 0.5)
			(connect_pads
				(clearance 0)
			)
			(min_thickness 0.25)
			(keepout
				(tracks allowed)
				(vias not_allowed)
				(pads allowed)
				(copperpour not_allowed)
				(footprints allowed)
			)
			(placement
				(enabled no)
				(sheetname "")
			)
			(fill
				(thermal_gap 0.5)
				(thermal_bridge_width 0.5)
				(island_removal_mode 0)
			)
			(polygon
				(pts
					(xy 28.3464 -99.7077) (xy 28.3464 -102.7303) (xy 25.4508 -102.7303) (xy 25.1206 -102.7303) (xy 25.1206 -99.7077)
					(xy 25.4508 -99.7077)
				)
			)
		)
	)
	(footprint ""
		(layer "F.Cu")
		(at 5.4102 -431.5968 90)
		(property "Reference" "R127"
			(at 0 0 90)
			(layer "F.SilkS")
			(hide yes)
			(effects
				(font
					(size 1.27 1.27)
				)
			)
		)
		(property "Value" "1K8R6J-GP"
			(at -0.0508 -4.8514 90)
			(unlocked yes)
			(layer "F.Fab")
			(hide yes)
			(effects
				(font
					(size 1.016 1.016)
					(thickness 0.1524)
				)
			)
		)
		(property "Device Type" "R1206H28"
			(at 0 -6.3754 90)
			(unlocked yes)
			(layer "F.Fab")
			(hide yes)
			(effects
				(font
					(size 1.016 1.016)
					(thickness 0.1524)
				)
			)
		)
		(duplicate_pad_numbers_are_jumpers no)
		(fp_line
			(start 1.016 -2.2352)
			(end 1.016 2.2352)
			(stroke
				(width 0.1524)
				(type default)
			)
			(layer "F.SilkS")
		)
		(fp_line
			(start -1.016 -2.2352)
			(end 1.016 -2.2352)
			(stroke
				(width 0.1524)
				(type default)
			)
			(layer "F.SilkS")
		)
		(fp_line
			(start 1.016 2.2352)
			(end -1.016 2.2352)
			(stroke
				(width 0.1524)
				(type default)
			)
			(layer "F.SilkS")
		)
		(fp_line
			(start -1.016 2.2352)
			(end -1.016 -2.2352)
			(stroke
				(width 0.1524)
				(type default)
			)
			(layer "F.SilkS")
		)
		(fp_rect
			(start -1.0922 2.3114)
			(end 1.0922 -2.3114)
			(stroke
				(width 0)
				(type default)
			)
			(fill no)
			(layer "F.CrtYd")
		)
		(fp_poly
			(pts
				(xy -1.0922 -2.3114) (xy 1.0922 -2.3114) (xy 1.0922 2.3114) (xy -1.0922 2.3114)
			)
			(stroke
				(width 0)
				(type default)
			)
			(fill no)
			(layer "F.Fab")
		)
		(pad "1" smd rect
			(at 0 -1.397 90)
			(size 1.651 1.27)
			(layers "F.Cu" "F.Mask" "F.Paste")
			(net "P12V")
		)
		(pad "2" smd rect
			(at 0 1.397 90)
			(size 1.651 1.27)
			(layers "F.Cu" "F.Mask" "F.Paste")
			(net "LED_DR_LED0_BLUE")
		)
	)
	(footprint ""
		(layer "F.Cu")
		(at 25.146 -248.412 180)
		(property "Reference" "PR55"
			(at 0 0 180)
			(layer "F.SilkS")
			(hide yes)
			(effects
				(font
					(size 1.27 1.27)
				)
			)
		)
		(property "Value" "100KR2F-L1-GP"
			(at 0.064008 -3.993896 180)
			(unlocked yes)
			(layer "F.Fab")
			(hide yes)
			(effects
				(font
					(size 1.016 1.016)
					(thickness 0.1524)
				)
			)
		)
		(property "Device Type" "R402H16"
			(at 0.064008 -5.517896 180)
			(unlocked yes)
			(layer "F.Fab")
			(hide yes)
			(effects
				(font
					(size 1.016 1.016)
					(thickness 0.1524)
				)
			)
		)
		(duplicate_pad_numbers_are_jumpers no)
		(fp_line
			(start 0.508 -0.9398)
			(end -0.508 -0.9398)
			(stroke
				(width 0.1524)
				(type default)
			)
			(layer "F.SilkS")
		)
		(fp_line
			(start -0.508 -0.9398)
			(end -0.508 0.9398)
			(stroke
				(width 0.1524)
				(type default)
			)
			(layer "F.SilkS")
		)
		(fp_rect
			(start -0.508 0.9398)
			(end 0.508 -0.9398)
			(stroke
				(width 0)
				(type default)
			)
			(fill no)
			(layer "F.CrtYd")
		)
		(fp_rect
			(start -0.508 0.9398)
			(end 0.508 -0.9398)
			(stroke
				(width 0)
				(type default)
			)
			(fill no)
			(layer "F.Fab")
		)
		(pad "1" smd custom
			(at 0 -0.4445 180)
			(size 0.1397 0.1397)
			(layers "F.Cu" "F.Mask" "F.Paste")
			(net "P3V3_LX_REV")
			(options
				(clearance outline)
				(anchor circle)
			)
			(primitives
				(gr_poly
					(pts
						(arc
							(start -0.1778 -0.2794)
							(mid -0.249642 -0.249642)
							(end -0.2794 -0.1778)
						)
						(arc
							(start -0.2794 0.1778)
							(mid -0.249642 0.249642)
							(end -0.1778 0.2794)
						)
						(arc
							(start 0.1778 0.2794)
							(mid 0.249642 0.249642)
							(end 0.2794 0.1778)
						)
						(arc
							(start 0.2794 -0.1778)
							(mid 0.249642 -0.249642)
							(end 0.1778 -0.2794)
						)
					)
					(width 0)
					(fill yes)
				)
			)
		)
		(pad "2" smd custom
			(at 0 0.4445 180)
			(size 0.1397 0.1397)
			(layers "F.Cu" "F.Mask" "F.Paste")
			(net "P3V3_FB")
			(options
				(clearance outline)
				(anchor circle)
			)
			(primitives
				(gr_poly
					(pts
						(arc
							(start -0.1778 -0.2794)
							(mid -0.249642 -0.249642)
							(end -0.2794 -0.1778)
						)
						(arc
							(start -0.2794 0.1778)
							(mid -0.249642 0.249642)
							(end -0.1778 0.2794)
						)
						(arc
							(start 0.1778 0.2794)
							(mid 0.249642 0.249642)
							(end 0.2794 0.1778)
						)
						(arc
							(start 0.2794 -0.1778)
							(mid 0.249642 -0.249642)
							(end 0.1778 -0.2794)
						)
					)
					(width 0)
					(fill yes)
				)
			)
		)
	)
	(footprint ""
		(layer "F.Cu")
		(at 37.4904 -252.6284)
		(property "Reference" "TP26"
			(at 0 0 0)
			(layer "F.SilkS")
			(hide yes)
			(effects
				(font
					(size 1.27 1.27)
				)
			)
		)
		(property "Value" "TPAD32-GP"
			(at 0 -3.166364 0)
			(unlocked yes)
			(layer "F.Fab")
			(hide yes)
			(effects
				(font
					(size 1.016 1.016)
					(thickness 0.1524)
				)
			)
		)
		(property "Device Type" "TPAD32"
			(at 0 -4.690618 0)
			(unlocked yes)
			(layer "F.Fab")
			(hide yes)
			(effects
				(font
					(size 1.016 1.016)
					(thickness 0.1524)
				)
			)
		)
		(duplicate_pad_numbers_are_jumpers no)
		(fp_poly
			(pts
				(arc
					(start 0.7112 0)
					(mid -0.7112 0)
					(end 0.7112 0)
				)
			)
			(stroke
				(width 0)
				(type default)
			)
			(fill no)
			(layer "F.CrtYd")
		)
		(fp_poly
			(pts
				(arc
					(start 0.7112 0)
					(mid -0.7112 0)
					(end 0.7112 0)
				)
			)
			(stroke
				(width 0)
				(type default)
			)
			(fill no)
			(layer "F.Fab")
		)
		(pad "1" smd circle
			(at 0 0)
			(size 0.8128 0.8128)
			(layers "F.Cu" "F.Mask" "F.Paste")
			(net "LED_DR_LED7_RESERVE")
		)
	)
	(footprint ""
		(layer "F.Cu")
		(at 20.675092 -288.278062 180)
		(property "Reference" "R99"
			(at 0 0 180)
			(layer "F.SilkS")
			(hide yes)
			(effects
				(font
					(size 1.27 1.27)
				)
			)
		)
		(property "Value" "27KR3F-GP"
			(at -0.0254 -2.5146 180)
			(unlocked yes)
			(layer "F.Fab")
			(hide yes)
			(effects
				(font
					(size 1.016 1.016)
					(thickness 0.1524)
				)
			)
		)
		(property "Device Type" "R603H22"
			(at -0.0254 -4.0386 180)
			(unlocked yes)
			(layer "F.Fab")
			(hide yes)
			(effects
				(font
					(size 1.016 1.016)
					(thickness 0.1524)
				)
			)
		)
		(duplicate_pad_numbers_are_jumpers no)
		(fp_line
			(start 0.2032 0)
			(end 0.4826 0)
			(stroke
				(width 0.2032)
				(type default)
			)
			(layer "F.SilkS")
		)
		(fp_line
			(start -0.4826 0)
			(end -0.2032 0)
			(stroke
				(width 0.2032)
				(type default)
			)
			(layer "F.SilkS")
		)
		(fp_rect
			(start -0.5842 1.3335)
			(end 0.5842 -1.3335)
			(stroke
				(width 0)
				(type default)
			)
			(fill no)
			(layer "F.CrtYd")
		)
		(fp_rect
			(start -0.5842 1.3335)
			(end 0.5842 -1.3335)
			(stroke
				(width 0)
				(type default)
			)
			(fill no)
			(layer "F.Fab")
		)
		(pad "1" smd custom
			(at 0 -0.762 180)
			(size 0.2159 0.2159)
			(layers "F.Cu" "F.Mask" "F.Paste")
			(net "FAN_TACH4")
			(options
				(clearance outline)
				(anchor circle)
			)
			(primitives
				(gr_poly
					(pts
						(arc
							(start -0.3302 -0.4318)
							(mid -0.402042 -0.402042)
							(end -0.4318 -0.3302)
						)
						(arc
							(start -0.4318 0.3302)
							(mid -0.402042 0.402042)
							(end -0.3302 0.4318)
						)
						(arc
							(start 0.3302 0.4318)
							(mid 0.402042 0.402042)
							(end 0.4318 0.3302)
						)
						(arc
							(start 0.4318 -0.3302)
							(mid 0.402042 -0.402042)
							(end 0.3302 -0.4318)
						)
					)
					(width 0)
					(fill yes)
				)
			)
		)
		(pad "2" smd custom
			(at 0 0.762 180)
			(size 0.2159 0.2159)
			(layers "F.Cu" "F.Mask" "F.Paste")
			(net "FANIN_4")
			(options
				(clearance outline)
				(anchor circle)
			)
			(primitives
				(gr_poly
					(pts
						(arc
							(start -0.3302 -0.4318)
							(mid -0.402042 -0.402042)
							(end -0.4318 -0.3302)
						)
						(arc
							(start -0.4318 0.3302)
							(mid -0.402042 0.402042)
							(end -0.3302 0.4318)
						)
						(arc
							(start 0.3302 0.4318)
							(mid 0.402042 0.402042)
							(end 0.4318 0.3302)
						)
						(arc
							(start 0.4318 -0.3302)
							(mid 0.402042 -0.402042)
							(end 0.3302 -0.4318)
						)
					)
					(width 0)
					(fill yes)
				)
			)
		)
	)
	(footprint ""
		(layer "F.Cu")
		(at 26.1366 -210.844384 180)
		(property "Reference" "R136"
			(at 0 0 180)
			(layer "F.SilkS")
			(hide yes)
			(effects
				(font
					(size 1.27 1.27)
				)
			)
		)
		(property "Value" "0R2J-2-GP"
			(at 0.064008 -3.993896 180)
			(unlocked yes)
			(layer "F.Fab")
			(hide yes)
			(effects
				(font
					(size 1.016 1.016)
					(thickness 0.1524)
				)
			)
		)
		(property "Device Type" "R402H16"
			(at 0.064008 -5.517896 180)
			(unlocked yes)
			(layer "F.Fab")
			(hide yes)
			(effects
				(font
					(size 1.016 1.016)
					(thickness 0.1524)
				)
			)
		)
		(duplicate_pad_numbers_are_jumpers no)
		(fp_line
			(start 0.508 -0.9398)
			(end -0.508 -0.9398)
			(stroke
				(width 0.1524)
				(type default)
			)
			(layer "F.SilkS")
		)
		(fp_line
			(start -0.508 -0.9398)
			(end -0.508 0.9398)
			(stroke
				(width 0.1524)
				(type default)
			)
			(layer "F.SilkS")
		)
		(fp_rect
			(start -0.508 0.9398)
			(end 0.508 -0.9398)
			(stroke
				(width 0)
				(type default)
			)
			(fill no)
			(layer "F.CrtYd")
		)
		(fp_rect
			(start -0.508 0.9398)
			(end 0.508 -0.9398)
			(stroke
				(width 0)
				(type default)
			)
			(fill no)
			(layer "F.Fab")
		)
		(pad "1" smd custom
			(at 0 -0.4445 180)
			(size 0.1397 0.1397)
			(layers "F.Cu" "F.Mask" "F.Paste")
			(net "PWM_OUT_FAN6_NET")
			(options
				(clearance outline)
				(anchor circle)
			)
			(primitives
				(gr_poly
					(pts
						(arc
							(start -0.1778 -0.2794)
							(mid -0.249642 -0.249642)
							(end -0.2794 -0.1778)
						)
						(arc
							(start -0.2794 0.1778)
							(mid -0.249642 0.249642)
							(end -0.1778 0.2794)
						)
						(arc
							(start 0.1778 0.2794)
							(mid 0.249642 0.249642)
							(end 0.2794 0.1778)
						)
						(arc
							(start 0.2794 -0.1778)
							(mid 0.249642 -0.249642)
							(end 0.1778 -0.2794)
						)
					)
					(width 0)
					(fill yes)
				)
			)
		)
		(pad "2" smd custom
			(at 0 0.4445 180)
			(size 0.1397 0.1397)
			(layers "F.Cu" "F.Mask" "F.Paste")
			(net "PWM_OUT_FAN6")
			(options
				(clearance outline)
				(anchor circle)
			)
			(primitives
				(gr_poly
					(pts
						(arc
							(start -0.1778 -0.2794)
							(mid -0.249642 -0.249642)
							(end -0.2794 -0.1778)
						)
						(arc
							(start -0.2794 0.1778)
							(mid -0.249642 0.249642)
							(end -0.1778 0.2794)
						)
						(arc
							(start 0.1778 0.2794)
							(mid 0.249642 0.249642)
							(end 0.2794 0.1778)
						)
						(arc
							(start 0.2794 -0.1778)
							(mid 0.249642 -0.249642)
							(end 0.1778 -0.2794)
						)
					)
					(width 0)
					(fill yes)
				)
			)
		)
	)
	(footprint ""
		(layer "F.Cu")
		(at 12.5984 -146.1008)
		(property "Reference" "R74"
			(at 0 0 0)
			(layer "F.SilkS")
			(hide yes)
			(effects
				(font
					(size 1.27 1.27)
				)
			)
		)
		(property "Value" "10KR2F-2-GP"
			(at 0.064008 -3.993896 0)
			(unlocked yes)
			(layer "F.Fab")
			(hide yes)
			(effects
				(font
					(size 1.016 1.016)
					(thickness 0.1524)
				)
			)
		)
		(property "Device Type" "R402H16"
			(at 0.064008 -5.517896 0)
			(unlocked yes)
			(layer "F.Fab")
			(hide yes)
			(effects
				(font
					(size 1.016 1.016)
					(thickness 0.1524)
				)
			)
		)
		(duplicate_pad_numbers_are_jumpers no)
		(fp_line
			(start -0.508 -0.9398)
			(end -0.508 0.9398)
			(stroke
				(width 0.1524)
				(type default)
			)
			(layer "F.SilkS")
		)
		(fp_line
			(start 0.508 -0.9398)
			(end -0.508 -0.9398)
			(stroke
				(width 0.1524)
				(type default)
			)
			(layer "F.SilkS")
		)
		(fp_rect
			(start -0.508 0.9398)
			(end 0.508 -0.9398)
			(stroke
				(width 0)
				(type default)
			)
			(fill no)
			(layer "F.CrtYd")
		)
		(fp_rect
			(start -0.508 0.9398)
			(end 0.508 -0.9398)
			(stroke
				(width 0)
				(type default)
			)
			(fill no)
			(layer "F.Fab")
		)
		(pad "1" smd custom
			(at 0 -0.4445)
			(size 0.1397 0.1397)
			(layers "F.Cu" "F.Mask" "F.Paste")
			(net "FANIN_10")
			(options
				(clearance outline)
				(anchor circle)
			)
			(primitives
				(gr_poly
					(pts
						(arc
							(start -0.1778 -0.2794)
							(mid -0.249642 -0.249642)
							(end -0.2794 -0.1778)
						)
						(arc
							(start -0.2794 0.1778)
							(mid -0.249642 0.249642)
							(end -0.1778 0.2794)
						)
						(arc
							(start 0.1778 0.2794)
							(mid 0.249642 0.249642)
							(end 0.2794 0.1778)
						)
						(arc
							(start 0.2794 -0.1778)
							(mid 0.249642 -0.249642)
							(end 0.1778 -0.2794)
						)
					)
					(width 0)
					(fill yes)
				)
			)
		)
		(pad "2" smd custom
			(at 0 0.4445)
			(size 0.1397 0.1397)
			(layers "F.Cu" "F.Mask" "F.Paste")
			(net "GND")
			(options
				(clearance outline)
				(anchor circle)
			)
			(primitives
				(gr_poly
					(pts
						(arc
							(start -0.1778 -0.2794)
							(mid -0.249642 -0.249642)
							(end -0.2794 -0.1778)
						)
						(arc
							(start -0.2794 0.1778)
							(mid -0.249642 0.249642)
							(end -0.1778 0.2794)
						)
						(arc
							(start 0.1778 0.2794)
							(mid 0.249642 0.249642)
							(end 0.2794 0.1778)
						)
						(arc
							(start 0.2794 -0.1778)
							(mid 0.249642 -0.249642)
							(end 0.1778 -0.2794)
						)
					)
					(width 0)
					(fill yes)
				)
			)
		)
	)
)
